FILE_TYPE = CONNECTIVITY;
{Allegro Design Entry HDL 16.6-p007 (v16-6-112F) 10/10/2012}
"PAGE_NUMBER" = 68;
0"NC";
1"UPI_CPU1_CPU0_P1P1_DP<19..0>";
2"UPI_CPU1_CPU0_P1P1_DN<19..0>";
3"UPI_CPU0_CPU1_P1P1_DP<19..0>";
4"UPI_CPU0_CPU1_P1P1_DN<19..0>";
5"UPI_CPU0_CPU1_P1P1_DP<0>";
6"UPI_CPU0_CPU1_P1P1_DN<1>";
7"UPI_CPU0_CPU1_P1P1_DN<2>";
8"UPI_CPU0_CPU1_P1P1_DN<3>";
9"UPI_CPU0_CPU1_P1P1_DN<4>";
10"UPI_CPU0_CPU1_P1P1_DN<5>";
11"UPI_CPU0_CPU1_P1P1_DN<6>";
12"UPI_CPU0_CPU1_P1P1_DN<7>";
13"UPI_CPU0_CPU1_P1P1_DN<0>";
14"UPI_CPU0_CPU1_P1P1_DP<1>";
15"UPI_CPU0_CPU1_P1P1_DP<2>";
16"UPI_CPU0_CPU1_P1P1_DP<3>";
17"UPI_CPU0_CPU1_P1P1_DP<4>";
18"UPI_CPU0_CPU1_P1P1_DP<5>";
19"UPI_CPU0_CPU1_P1P1_DP<6>";
20"UPI_CPU0_CPU1_P1P1_DP<7>";
21"UPI_CPU0_CPU1_P1P1_DN<8>";
22"UPI_CPU0_CPU1_P1P1_DP<9>";
23"UPI_CPU0_CPU1_P1P1_DP<10>";
24"UPI_CPU0_CPU1_P1P1_DN<11>";
25"UPI_CPU0_CPU1_P1P1_DN<12>";
26"UPI_CPU0_CPU1_P1P1_DN<13>";
27"UPI_CPU0_CPU1_P1P1_DP<14>";
28"UPI_CPU0_CPU1_P1P1_DP<15>";
29"UPI_CPU0_CPU1_P1P1_DP<16>";
30"UPI_CPU0_CPU1_P1P1_DP<17>";
31"UPI_CPU0_CPU1_P1P1_DN<18>";
32"UPI_CPU0_CPU1_P1P1_DN<19>";
33"UPI_CPU0_CPU1_P1P1_DP<8>";
34"UPI_CPU0_CPU1_P1P1_DN<9>";
35"UPI_CPU0_CPU1_P1P1_DN<10>";
36"UPI_CPU0_CPU1_P1P1_DP<11>";
37"UPI_CPU0_CPU1_P1P1_DP<12>";
38"UPI_CPU0_CPU1_P1P1_DP<13>";
39"UPI_CPU0_CPU1_P1P1_DN<14>";
40"UPI_CPU0_CPU1_P1P1_DN<15>";
41"UPI_CPU0_CPU1_P1P1_DN<16>";
42"UPI_CPU0_CPU1_P1P1_DN<17>";
43"UPI_CPU0_CPU1_P1P1_DP<18>";
44"UPI_CPU0_CPU1_P1P1_DP<19>";
45"UPI_CPU1_CPU0_P1P1_DP<0>";
46"UPI_CPU1_CPU0_P1P1_DP<1>";
47"UPI_CPU1_CPU0_P1P1_DN<2>";
48"UPI_CPU1_CPU0_P1P1_DN<3>";
49"UPI_CPU1_CPU0_P1P1_DN<4>";
50"UPI_CPU1_CPU0_P1P1_DN<5>";
51"UPI_CPU1_CPU0_P1P1_DP<6>";
52"UPI_CPU1_CPU0_P1P1_DP<7>";
53"UPI_CPU1_CPU0_P1P1_DN<0>";
54"UPI_CPU1_CPU0_P1P1_DN<1>";
55"UPI_CPU1_CPU0_P1P1_DP<2>";
56"UPI_CPU1_CPU0_P1P1_DP<3>";
57"UPI_CPU1_CPU0_P1P1_DP<4>";
58"UPI_CPU1_CPU0_P1P1_DP<5>";
59"UPI_CPU1_CPU0_P1P1_DN<6>";
60"UPI_CPU1_CPU0_P1P1_DN<7>";
61"UPI_CPU1_CPU0_P1P1_DN<8>";
62"UPI_CPU1_CPU0_P1P1_DP<9>";
63"UPI_CPU1_CPU0_P1P1_DP<10>";
64"UPI_CPU1_CPU0_P1P1_DN<11>";
65"UPI_CPU1_CPU0_P1P1_DP<12>";
66"UPI_CPU1_CPU0_P1P1_DP<13>";
67"UPI_CPU1_CPU0_P1P1_DP<14>";
68"UPI_CPU1_CPU0_P1P1_DP<15>";
69"UPI_CPU1_CPU0_P1P1_DP<16>";
70"UPI_CPU1_CPU0_P1P1_DP<17>";
71"UPI_CPU1_CPU0_P1P1_DN<18>";
72"UPI_CPU1_CPU0_P1P1_DN<19>";
73"UPI_CPU1_CPU0_P1P1_DP<8>";
74"UPI_CPU1_CPU0_P1P1_DN<9>";
75"UPI_CPU1_CPU0_P1P1_DN<10>";
76"UPI_CPU1_CPU0_P1P1_DP<11>";
77"UPI_CPU1_CPU0_P1P1_DN<12>";
78"UPI_CPU1_CPU0_P1P1_DN<13>";
79"UPI_CPU1_CPU0_P1P1_DN<14>";
80"UPI_CPU1_CPU0_P1P1_DN<15>";
81"UPI_CPU1_CPU0_P1P1_DN<16>";
82"UPI_CPU1_CPU0_P1P1_DN<17>";
83"UPI_CPU1_CPU0_P1P1_DP<18>";
84"UPI_CPU1_CPU0_P1P1_DP<19>";
%"TAP"
"1","(-5725,1900)","2","mstr_standard","I10";
;
HDL_TAP"TRUE"
BODY_TYPE"PLUMBING"
CDS_LIB"mstr_standard";
"B \NAC \NWC"4;
"S \NAC"
BN"5"10;
%"TAP"
"1","(-2950,1700)","0","mstr_standard","I100";
;
HDL_TAP"TRUE"
BODY_TYPE"PLUMBING"
CDS_LIB"mstr_standard";
"B \NAC \NWC"1;
"S \NAC"
BN"1"46;
%"TAP"
"1","(-2950,2950)","0","mstr_standard","I101";
;
HDL_TAP"TRUE"
BODY_TYPE"PLUMBING"
CDS_LIB"mstr_standard";
"B \NAC \NWC"1;
"S \NAC"
BN"5"58;
%"TAP"
"1","(-2950,1950)","0","mstr_standard","I102";
;
HDL_TAP"TRUE"
BODY_TYPE"PLUMBING"
CDS_LIB"mstr_standard";
"B \NAC \NWC"1;
"S \NAC"
BN"6"51;
%"TAP"
"1","(-2950,2000)","0","mstr_standard","I103";
;
HDL_TAP"TRUE"
BODY_TYPE"PLUMBING"
CDS_LIB"mstr_standard";
"B \NAC \NWC"1;
"S \NAC"
BN"7"52;
%"TAP"
"1","(-2950,2050)","0","mstr_standard","I104";
;
HDL_TAP"TRUE"
BODY_TYPE"PLUMBING"
CDS_LIB"mstr_standard";
"B \NAC \NWC"1;
"S \NAC"
BN"8"73;
%"TAP"
"1","(-2950,3150)","0","mstr_standard","I105";
;
HDL_TAP"TRUE"
BODY_TYPE"PLUMBING"
CDS_LIB"mstr_standard";
"B \NAC \NWC"1;
"S \NAC"
BN"9"62;
%"TAP"
"1","(-2950,2200)","0","mstr_standard","I106";
;
HDL_TAP"TRUE"
BODY_TYPE"PLUMBING"
CDS_LIB"mstr_standard";
"B \NAC \NWC"1;
"S \NAC"
BN"11"76;
%"TAP"
"1","(-2950,3350)","0","mstr_standard","I107";
;
HDL_TAP"TRUE"
BODY_TYPE"PLUMBING"
CDS_LIB"mstr_standard";
"B \NAC \NWC"1;
"S \NAC"
BN"13"66;
%"TAP"
"1","(-2950,3400)","0","mstr_standard","I108";
;
HDL_TAP"TRUE"
BODY_TYPE"PLUMBING"
CDS_LIB"mstr_standard";
"B \NAC \NWC"1;
"S \NAC"
BN"14"67;
%"TAP"
"1","(-2950,3450)","0","mstr_standard","I109";
;
HDL_TAP"TRUE"
BODY_TYPE"PLUMBING"
CDS_LIB"mstr_standard";
"B \NAC \NWC"1;
"S \NAC"
BN"15"68;
%"TAP"
"1","(-5725,2000)","2","mstr_standard","I11";
;
HDL_TAP"TRUE"
BODY_TYPE"PLUMBING"
CDS_LIB"mstr_standard";
"B \NAC \NWC"4;
"S \NAC"
BN"7"12;
%"TAP"
"1","(-2950,2550)","0","mstr_standard","I110";
;
HDL_TAP"TRUE"
BODY_TYPE"PLUMBING"
CDS_LIB"mstr_standard";
"B \NAC \NWC"1;
"S \NAC"
BN"18"83;
%"TAP"
"1","(-2950,2600)","0","mstr_standard","I111";
;
HDL_TAP"TRUE"
BODY_TYPE"PLUMBING"
CDS_LIB"mstr_standard";
"B \NAC \NWC"1;
"S \NAC"
BN"19"84;
%"TAP"
"1","(-2625,2700)","0","mstr_standard","I112";
;
HDL_TAP"TRUE"
BODY_TYPE"PLUMBING"
CDS_LIB"mstr_standard";
"B \NAC \NWC"2;
"S \NAC"
BN"0"53;
%"TAP"
"1","(-2625,2750)","0","mstr_standard","I113";
;
HDL_TAP"TRUE"
BODY_TYPE"PLUMBING"
CDS_LIB"mstr_standard";
"B \NAC \NWC"2;
"S \NAC"
BN"1"54;
%"TAP"
"1","(-2625,1900)","0","mstr_standard","I114";
;
HDL_TAP"TRUE"
BODY_TYPE"PLUMBING"
CDS_LIB"mstr_standard";
"B \NAC \NWC"2;
"S \NAC"
BN"5"50;
%"TAP"
"1","(-2625,3000)","0","mstr_standard","I115";
;
HDL_TAP"TRUE"
BODY_TYPE"PLUMBING"
CDS_LIB"mstr_standard";
"B \NAC \NWC"2;
"S \NAC"
BN"6"59;
%"TAP"
"1","(-2625,3050)","0","mstr_standard","I116";
;
HDL_TAP"TRUE"
BODY_TYPE"PLUMBING"
CDS_LIB"mstr_standard";
"B \NAC \NWC"2;
"S \NAC"
BN"7"60;
%"TAP"
"1","(-2625,3100)","0","mstr_standard","I117";
;
HDL_TAP"TRUE"
BODY_TYPE"PLUMBING"
CDS_LIB"mstr_standard";
"B \NAC \NWC"2;
"S \NAC"
BN"8"61;
%"TAP"
"1","(-2625,2100)","0","mstr_standard","I118";
;
HDL_TAP"TRUE"
BODY_TYPE"PLUMBING"
CDS_LIB"mstr_standard";
"B \NAC \NWC"2;
"S \NAC"
BN"9"74;
%"TAP"
"1","(-2625,3250)","0","mstr_standard","I119";
;
HDL_TAP"TRUE"
BODY_TYPE"PLUMBING"
CDS_LIB"mstr_standard";
"B \NAC \NWC"2;
"S \NAC"
BN"11"64;
%"TAP"
"1","(-2625,2300)","0","mstr_standard","I120";
;
HDL_TAP"TRUE"
BODY_TYPE"PLUMBING"
CDS_LIB"mstr_standard";
"B \NAC \NWC"2;
"S \NAC"
BN"13"78;
%"TAP"
"1","(-2625,2350)","0","mstr_standard","I121";
;
HDL_TAP"TRUE"
BODY_TYPE"PLUMBING"
CDS_LIB"mstr_standard";
"B \NAC \NWC"2;
"S \NAC"
BN"14"79;
%"TAP"
"1","(-2625,2400)","0","mstr_standard","I122";
;
HDL_TAP"TRUE"
BODY_TYPE"PLUMBING"
CDS_LIB"mstr_standard";
"B \NAC \NWC"2;
"S \NAC"
BN"15"80;
%"TAP"
"1","(-2625,3600)","0","mstr_standard","I123";
;
HDL_TAP"TRUE"
BODY_TYPE"PLUMBING"
CDS_LIB"mstr_standard";
"B \NAC \NWC"2;
"S \NAC"
BN"18"71;
%"TAP"
"1","(-2625,3650)","0","mstr_standard","I124";
;
HDL_TAP"TRUE"
BODY_TYPE"PLUMBING"
CDS_LIB"mstr_standard";
"B \NAC \NWC"2;
"S \NAC"
BN"19"72;
%"SKX_EXT_B"
"14","(-4100,2650)","0","chpset_lib","I125";
;
CDS_SEC"14"
CDS_LOCATION"U2D1"
SEC"14"
CDS_LIB"chpset_lib"
SEC_TYPE"BGA1"
PACK_TYPE"BGA1"
MATERIAL"IC"
PART_NUMBER"TBD"
LOCATION"U2D1";
"UPI1_TX_DP<0>"
$PN"P3"53;
"UPI1_TX_DP<1>"
$PN"K3"54;
"UPI1_TX_DP<2>"
$PN"M5"55;
"UPI1_TX_DP<3>"
$PN"H5"56;
"UPI1_TX_DP<4>"
$PN"F7"57;
"UPI1_TX_DP<5>"
$PN"K7"58;
"UPI1_TX_DP<6>"
$PN"J8"59;
"UPI1_TX_DP<7>"
$PN"F9"60;
"UPI1_TX_DP<8>"
$PN"E10"61;
"UPI1_TX_DP<9>"
$PN"H9"62;
"UPI1_TX_DP<10>"
$PN"G12"63;
"UPI1_TX_DP<11>"
$PN"F13"64;
"UPI1_TX_DP<12>"
$PN"E14"65;
"UPI1_TX_DP<13>"
$PN"H15"66;
"UPI1_TX_DP<14>"
$PN"G16"67;
"UPI1_TX_DP<15>"
$PN"L18"68;
"UPI1_TX_DP<16>"
$PN"J18"69;
"UPI1_TX_DP<17>"
$PN"H19"70;
"UPI1_TX_DP<18>"
$PN"G20"71;
"UPI1_TX_DP<19>"
$PN"K21"72;
"UPI1_TX_DN<0>"
$PN"M3"45;
"UPI1_TX_DN<1>"
$PN"L4"46;
"UPI1_TX_DN<2>"
$PN"K5"47;
"UPI1_TX_DN<3>"
$PN"J6"48;
"UPI1_TX_DN<4>"
$PN"G6"49;
"UPI1_TX_DN<5>"
$PN"H7"50;
"UPI1_TX_DN<6>"
$PN"K9"51;
"UPI1_TX_DN<7>"
$PN"D9"52;
"UPI1_TX_DN<8>"
$PN"F11"73;
"UPI1_TX_DN<9>"
$PN"G10"74;
"UPI1_TX_DN<10>"
$PN"E12"75;
"UPI1_TX_DN<11>"
$PN"G14"76;
"UPI1_TX_DN<12>"
$PN"D15"77;
"UPI1_TX_DN<13>"
$PN"F15"78;
"UPI1_TX_DN<14>"
$PN"H17"79;
"UPI1_TX_DN<15>"
$PN"K19"80;
"UPI1_TX_DN<16>"
$PN"G18"81;
"UPI1_TX_DN<17>"
$PN"J20"82;
"UPI1_TX_DN<18>"
$PN"F21"83;
"UPI1_TX_DN<19>"
$PN"H21"84;
"UPI1_RX_DP<0>"
$PN"R6"13;
"UPI1_RX_DP<1>"
$PN"T7"14;
"UPI1_RX_DP<2>"
$PN"U8"15;
"UPI1_RX_DP<3>"
$PN"R8"16;
"UPI1_RX_DP<4>"
$PN"N10"17;
"UPI1_RX_DP<5>"
$PN"U10"18;
"UPI1_RX_DP<6>"
$PN"T11"19;
"UPI1_RX_DP<7>"
$PN"N12"20;
"UPI1_RX_DP<8>"
$PN"M13"21;
"UPI1_RX_DP<9>"
$PN"P13"22;
"UPI1_RX_DP<10>"
$PN"T15"23;
"UPI1_RX_DP<11>"
$PN"N16"24;
"UPI1_RX_DP<12>"
$PN"W16"25;
"UPI1_RX_DP<13>"
$PN"V17"26;
"UPI1_RX_DP<14>"
$PN"P19"27;
"UPI1_RX_DP<15>"
$PN"T19"28;
"UPI1_RX_DP<16>"
$PN"T21"29;
"UPI1_RX_DP<17>"
$PN"Y19"30;
"UPI1_RX_DP<18>"
$PN"W20"31;
"UPI1_RX_DP<19>"
$PN"AA20"32;
"UPI1_RX_DN<0>"
$PN"T5"5;
"UPI1_RX_DN<1>"
$PN"P7"6;
"UPI1_RX_DN<2>"
$PN"V7"7;
"UPI1_RX_DN<3>"
$PN"T9"8;
"UPI1_RX_DN<4>"
$PN"P9"9;
"UPI1_RX_DN<5>"
$PN"R10"10;
"UPI1_RX_DN<6>"
$PN"U12"11;
"UPI1_RX_DN<7>"
$PN"L12"12;
"UPI1_RX_DN<8>"
$PN"N14"33;
"UPI1_RX_DN<9>"
$PN"R12"34;
"UPI1_RX_DN<10>"
$PN"R16"35;
"UPI1_RX_DN<11>"
$PN"P17"36;
"UPI1_RX_DN<12>"
$PN"U16"37;
"UPI1_RX_DN<13>"
$PN"W18"38;
"UPI1_RX_DN<14>"
$PN"R20"39;
"UPI1_RX_DN<15>"
$PN"U18"40;
"UPI1_RX_DN<16>"
$PN"P21"41;
"UPI1_RX_DN<17>"
$PN"V19"42;
"UPI1_RX_DN<18>"
$PN"Y21"43;
"UPI1_RX_DN<19>"
$PN"AB19"44;
%"TAP"
"1","(-5725,2100)","2","mstr_standard","I13";
;
HDL_TAP"TRUE"
BODY_TYPE"PLUMBING"
CDS_LIB"mstr_standard";
"B \NAC \NWC"4;
"S \NAC"
BN"9"34;
%"TAP"
"1","(-5725,2150)","2","mstr_standard","I14";
;
HDL_TAP"TRUE"
BODY_TYPE"PLUMBING"
CDS_LIB"mstr_standard";
"B \NAC \NWC"4;
"S \NAC"
BN"10"35;
%"TAP"
"1","(-5725,2350)","2","mstr_standard","I18";
;
HDL_TAP"TRUE"
BODY_TYPE"PLUMBING"
CDS_LIB"mstr_standard";
"B \NAC \NWC"4;
"S \NAC"
BN"14"39;
%"TAP"
"1","(-5725,2500)","2","mstr_standard","I21";
;
HDL_TAP"TRUE"
BODY_TYPE"PLUMBING"
CDS_LIB"mstr_standard";
"B \NAC \NWC"4;
"S \NAC"
BN"17"42;
%"TAP"
"1","(-5725,3600)","2","mstr_standard","I22";
;
HDL_TAP"TRUE"
BODY_TYPE"PLUMBING"
CDS_LIB"mstr_standard";
"B \NAC \NWC"4;
"S \NAC"
BN"18"31;
%"TAP"
"1","(-5275,2800)","2","mstr_standard","I26";
;
HDL_TAP"TRUE"
BODY_TYPE"PLUMBING"
CDS_LIB"mstr_standard";
"B \NAC \NWC"3;
"S \NAC"
BN"2"15;
%"TAP"
"1","(-5275,2850)","2","mstr_standard","I27";
;
HDL_TAP"TRUE"
BODY_TYPE"PLUMBING"
CDS_LIB"mstr_standard";
"B \NAC \NWC"3;
"S \NAC"
BN"3"16;
%"TAP"
"1","(-5275,2900)","2","mstr_standard","I28";
;
HDL_TAP"TRUE"
BODY_TYPE"PLUMBING"
CDS_LIB"mstr_standard";
"B \NAC \NWC"3;
"S \NAC"
BN"4"17;
%"TAP"
"1","(-5275,2950)","2","mstr_standard","I29";
;
HDL_TAP"TRUE"
BODY_TYPE"PLUMBING"
CDS_LIB"mstr_standard";
"B \NAC \NWC"3;
"S \NAC"
BN"5"18;
%"TAP"
"1","(-5275,3000)","2","mstr_standard","I30";
;
HDL_TAP"TRUE"
BODY_TYPE"PLUMBING"
CDS_LIB"mstr_standard";
"B \NAC \NWC"3;
"S \NAC"
BN"6"19;
%"TAP"
"1","(-5275,3050)","2","mstr_standard","I31";
;
HDL_TAP"TRUE"
BODY_TYPE"PLUMBING"
CDS_LIB"mstr_standard";
"B \NAC \NWC"3;
"S \NAC"
BN"7"20;
%"TAP"
"1","(-5275,2050)","2","mstr_standard","I32";
;
HDL_TAP"TRUE"
BODY_TYPE"PLUMBING"
CDS_LIB"mstr_standard";
"B \NAC \NWC"3;
"S \NAC"
BN"8"33;
%"TAP"
"1","(-5275,3150)","2","mstr_standard","I33";
;
HDL_TAP"TRUE"
BODY_TYPE"PLUMBING"
CDS_LIB"mstr_standard";
"B \NAC \NWC"3;
"S \NAC"
BN"9"22;
%"TAP"
"1","(-5275,3200)","2","mstr_standard","I34";
;
HDL_TAP"TRUE"
BODY_TYPE"PLUMBING"
CDS_LIB"mstr_standard";
"B \NAC \NWC"3;
"S \NAC"
BN"10"23;
%"TAP"
"1","(-5275,2200)","2","mstr_standard","I35";
;
HDL_TAP"TRUE"
BODY_TYPE"PLUMBING"
CDS_LIB"mstr_standard";
"B \NAC \NWC"3;
"S \NAC"
BN"11"36;
%"TAP"
"1","(-5275,2250)","2","mstr_standard","I36";
;
HDL_TAP"TRUE"
BODY_TYPE"PLUMBING"
CDS_LIB"mstr_standard";
"B \NAC \NWC"3;
"S \NAC"
BN"12"37;
%"TAP"
"1","(-5275,2300)","2","mstr_standard","I37";
;
HDL_TAP"TRUE"
BODY_TYPE"PLUMBING"
CDS_LIB"mstr_standard";
"B \NAC \NWC"3;
"S \NAC"
BN"13"38;
%"TAP"
"1","(-5275,3400)","2","mstr_standard","I38";
;
HDL_TAP"TRUE"
BODY_TYPE"PLUMBING"
CDS_LIB"mstr_standard";
"B \NAC \NWC"3;
"S \NAC"
BN"14"27;
%"TAP"
"1","(-5275,3450)","2","mstr_standard","I39";
;
HDL_TAP"TRUE"
BODY_TYPE"PLUMBING"
CDS_LIB"mstr_standard";
"B \NAC \NWC"3;
"S \NAC"
BN"15"28;
%"TAP"
"1","(-5275,3500)","2","mstr_standard","I40";
;
HDL_TAP"TRUE"
BODY_TYPE"PLUMBING"
CDS_LIB"mstr_standard";
"B \NAC \NWC"3;
"S \NAC"
BN"16"29;
%"TAP"
"1","(-5275,3550)","2","mstr_standard","I41";
;
HDL_TAP"TRUE"
BODY_TYPE"PLUMBING"
CDS_LIB"mstr_standard";
"B \NAC \NWC"3;
"S \NAC"
BN"17"30;
%"TAP"
"1","(-5275,2550)","2","mstr_standard","I42";
;
HDL_TAP"TRUE"
BODY_TYPE"PLUMBING"
CDS_LIB"mstr_standard";
"B \NAC \NWC"3;
"S \NAC"
BN"18"43;
%"TAP"
"1","(-5275,2600)","2","mstr_standard","I43";
;
HDL_TAP"TRUE"
BODY_TYPE"PLUMBING"
CDS_LIB"mstr_standard";
"B \NAC \NWC"3;
"S \NAC"
BN"19"44;
%"TAP"
"1","(-2625,1800)","0","mstr_standard","I46";
;
HDL_TAP"TRUE"
BODY_TYPE"PLUMBING"
CDS_LIB"mstr_standard";
"B \NAC \NWC"2;
"S \NAC"
BN"3"48;
%"TAP"
"1","(-2625,1750)","0","mstr_standard","I47";
;
HDL_TAP"TRUE"
BODY_TYPE"PLUMBING"
CDS_LIB"mstr_standard";
"B \NAC \NWC"2;
"S \NAC"
BN"2"47;
%"TAP"
"1","(-2625,1850)","0","mstr_standard","I48";
;
HDL_TAP"TRUE"
BODY_TYPE"PLUMBING"
CDS_LIB"mstr_standard";
"B \NAC \NWC"2;
"S \NAC"
BN"4"49;
%"TAP"
"1","(-5725,1800)","2","mstr_standard","I5";
;
HDL_TAP"TRUE"
BODY_TYPE"PLUMBING"
CDS_LIB"mstr_standard";
"B \NAC \NWC"4;
"S \NAC"
BN"3"8;
%"TAP"
"1","(-2625,2150)","0","mstr_standard","I54";
;
HDL_TAP"TRUE"
BODY_TYPE"PLUMBING"
CDS_LIB"mstr_standard";
"B \NAC \NWC"2;
"S \NAC"
BN"10"75;
%"TAP"
"1","(-2625,2250)","0","mstr_standard","I56";
;
HDL_TAP"TRUE"
BODY_TYPE"PLUMBING"
CDS_LIB"mstr_standard";
"B \NAC \NWC"2;
"S \NAC"
BN"12"77;
%"TAP"
"1","(-5725,1750)","2","mstr_standard","I6";
;
HDL_TAP"TRUE"
BODY_TYPE"PLUMBING"
CDS_LIB"mstr_standard";
"B \NAC \NWC"4;
"S \NAC"
BN"2"7;
%"TAP"
"1","(-2625,2500)","0","mstr_standard","I60";
;
HDL_TAP"TRUE"
BODY_TYPE"PLUMBING"
CDS_LIB"mstr_standard";
"B \NAC \NWC"2;
"S \NAC"
BN"17"82;
%"TAP"
"1","(-2625,2450)","0","mstr_standard","I61";
;
HDL_TAP"TRUE"
BODY_TYPE"PLUMBING"
CDS_LIB"mstr_standard";
"B \NAC \NWC"2;
"S \NAC"
BN"16"81;
%"TAP"
"1","(-2950,2800)","0","mstr_standard","I66";
;
HDL_TAP"TRUE"
BODY_TYPE"PLUMBING"
CDS_LIB"mstr_standard";
"B \NAC \NWC"1;
"S \NAC"
BN"2"55;
%"TAP"
"1","(-2950,2850)","0","mstr_standard","I67";
;
HDL_TAP"TRUE"
BODY_TYPE"PLUMBING"
CDS_LIB"mstr_standard";
"B \NAC \NWC"1;
"S \NAC"
BN"3"56;
%"TAP"
"1","(-2950,2900)","0","mstr_standard","I69";
;
HDL_TAP"TRUE"
BODY_TYPE"PLUMBING"
CDS_LIB"mstr_standard";
"B \NAC \NWC"1;
"S \NAC"
BN"4"57;
%"TAP"
"1","(-2950,3200)","0","mstr_standard","I74";
;
HDL_TAP"TRUE"
BODY_TYPE"PLUMBING"
CDS_LIB"mstr_standard";
"B \NAC \NWC"1;
"S \NAC"
BN"10"63;
%"TAP"
"1","(-2950,3300)","0","mstr_standard","I76";
;
HDL_TAP"TRUE"
BODY_TYPE"PLUMBING"
CDS_LIB"mstr_standard";
"B \NAC \NWC"1;
"S \NAC"
BN"12"65;
%"TAP"
"1","(-2950,3500)","0","mstr_standard","I80";
;
HDL_TAP"TRUE"
BODY_TYPE"PLUMBING"
CDS_LIB"mstr_standard";
"B \NAC \NWC"1;
"S \NAC"
BN"16"69;
%"TAP"
"1","(-2950,3550)","0","mstr_standard","I82";
;
HDL_TAP"TRUE"
BODY_TYPE"PLUMBING"
CDS_LIB"mstr_standard";
"B \NAC \NWC"1;
"S \NAC"
BN"17"70;
%"TAP"
"1","(-5725,2700)","2","mstr_standard","I86";
;
HDL_TAP"TRUE"
BODY_TYPE"PLUMBING"
CDS_LIB"mstr_standard";
"B \NAC \NWC"4;
"S \NAC"
BN"0"13;
%"TAP"
"1","(-5725,1700)","2","mstr_standard","I87";
;
HDL_TAP"TRUE"
BODY_TYPE"PLUMBING"
CDS_LIB"mstr_standard";
"B \NAC \NWC"4;
"S \NAC"
BN"1"6;
%"TAP"
"1","(-5275,1650)","2","mstr_standard","I88";
;
HDL_TAP"TRUE"
BODY_TYPE"PLUMBING"
CDS_LIB"mstr_standard";
"B \NAC \NWC"3;
"S \NAC"
BN"0"5;
%"TAP"
"1","(-5275,2750)","2","mstr_standard","I89";
;
HDL_TAP"TRUE"
BODY_TYPE"PLUMBING"
CDS_LIB"mstr_standard";
"B \NAC \NWC"3;
"S \NAC"
BN"1"14;
%"TAP"
"1","(-5725,1850)","2","mstr_standard","I90";
;
HDL_TAP"TRUE"
BODY_TYPE"PLUMBING"
CDS_LIB"mstr_standard";
"B \NAC \NWC"4;
"S \NAC"
BN"4"9;
%"TAP"
"1","(-5725,1950)","2","mstr_standard","I91";
;
HDL_TAP"TRUE"
BODY_TYPE"PLUMBING"
CDS_LIB"mstr_standard";
"B \NAC \NWC"4;
"S \NAC"
BN"6"11;
%"TAP"
"1","(-5725,3100)","2","mstr_standard","I92";
;
HDL_TAP"TRUE"
BODY_TYPE"PLUMBING"
CDS_LIB"mstr_standard";
"B \NAC \NWC"4;
"S \NAC"
BN"8"21;
%"TAP"
"1","(-5725,3250)","2","mstr_standard","I93";
;
HDL_TAP"TRUE"
BODY_TYPE"PLUMBING"
CDS_LIB"mstr_standard";
"B \NAC \NWC"4;
"S \NAC"
BN"11"24;
%"TAP"
"1","(-5725,3300)","2","mstr_standard","I94";
;
HDL_TAP"TRUE"
BODY_TYPE"PLUMBING"
CDS_LIB"mstr_standard";
"B \NAC \NWC"4;
"S \NAC"
BN"12"25;
%"TAP"
"1","(-5725,3350)","2","mstr_standard","I95";
;
HDL_TAP"TRUE"
BODY_TYPE"PLUMBING"
CDS_LIB"mstr_standard";
"B \NAC \NWC"4;
"S \NAC"
BN"13"26;
%"TAP"
"1","(-5725,2400)","2","mstr_standard","I96";
;
HDL_TAP"TRUE"
BODY_TYPE"PLUMBING"
CDS_LIB"mstr_standard";
"B \NAC \NWC"4;
"S \NAC"
BN"15"40;
%"TAP"
"1","(-5725,2450)","2","mstr_standard","I97";
;
HDL_TAP"TRUE"
BODY_TYPE"PLUMBING"
CDS_LIB"mstr_standard";
"B \NAC \NWC"4;
"S \NAC"
BN"16"41;
%"TAP"
"1","(-5725,3650)","2","mstr_standard","I98";
;
HDL_TAP"TRUE"
BODY_TYPE"PLUMBING"
CDS_LIB"mstr_standard";
"B \NAC \NWC"4;
"S \NAC"
BN"19"32;
%"TAP"
"1","(-2950,1650)","0","mstr_standard","I99";
;
HDL_TAP"TRUE"
BODY_TYPE"PLUMBING"
CDS_LIB"mstr_standard";
"B \NAC \NWC"1;
"S \NAC"
BN"0"45;
END.
